(kicad_pcb
	(version 20221018)
	(generator pcbnew)
	(general
    (thickness 1.62)
  )
	(paper "A4")
	(title_block
    (title "ECP5 - Datacenter Secure Control Module (DC-SCM)")
    (date "2024-07-01")
    (rev "1.2.1")
		(comment 9 "footprints 118-125 of 506")
	)
	(layers
    (0 "F.Cu" signal)
    (1 "In1.Cu" power)
    (2 "In2.Cu" signal)
    (3 "In3.Cu" power)
    (4 "In4.Cu" power)
    (5 "In5.Cu" signal)
    (6 "In6.Cu" power)
    (31 "B.Cu" signal)
    (32 "B.Adhes" user "B.Adhesive")
    (33 "F.Adhes" user "F.Adhesive")
    (34 "B.Paste" user)
    (35 "F.Paste" user)
    (36 "B.SilkS" user "B.Silkscreen")
    (37 "F.SilkS" user "F.Silkscreen")
    (38 "B.Mask" user)
    (39 "F.Mask" user)
    (40 "Dwgs.User" user "User.Drawings")
    (41 "Cmts.User" user "User.Comments")
    (42 "Eco1.User" user "User.Eco1")
    (43 "Eco2.User" user "User.Eco2")
    (44 "Edge.Cuts" user)
    (45 "Margin" user)
    (46 "B.CrtYd" user "B.Courtyard")
    (47 "F.CrtYd" user "F.Courtyard")
    (48 "B.Fab" user)
    (49 "F.Fab" user)
  )
	(footprint "antmicro-footprints:QFN-8_2x1.5mm" (layer "F.Cu")
    (at 77.15 86.15 90)
    (property "Author" "Antmicro")
    (property "License" "Apache-2.0")
    (property "MPN" "TPS62823DLCT")
    (property "Manufacturer" "Texas Instruments")
    (property "Sheetfile" "power-supply.kicad_sch")
    (property "Sheetname" "Power supply")
    (property "ki_description" "DC/DC converter")
    (property "ki_keywords" "SMT, PMIC, IC, SWITCHING, VOLTAGE, REGULATOR, DC-DC")
    (attr smd)
    (fp_text reference "U19" (at -1.59 -0.02 180) (layer "F.SilkS")
        (effects (font (size 0.7 0.7) (thickness 0.127)))
    )
    (fp_text value "TPS62823DLCT" (at 0 2.075 90) (layer "F.Fab")
        (effects (font (size 1 1) (thickness 0.15)))
    )
    (fp_text user "License: Apache-2.0" (at -1.651 6.475 90) (layer "F.Fab") hide
        (effects (font (size 0.7 0.7) (thickness 0.15)) (justify left bottom))
    )
    (fp_text user "${REFERENCE}" (at 0 0 90) (layer "F.Fab")
        (effects (font (size 0.5 0.5) (thickness 0.075)))
    )
    (fp_text user "Author: Antmicro" (at -1.651 5.275 90) (layer "F.Fab") hide
        (effects (font (size 0.7 0.7) (thickness 0.15)) (justify left bottom))
    )
    (fp_line (start -0.9 1.05) (end 0.9 1.05)
      (stroke (width 0.15) (type solid)) (layer "F.SilkS"))
    (fp_line (start -0.25 -1.05) (end 0.9 -1.05)
      (stroke (width 0.15) (type solid)) (layer "F.SilkS"))
    (fp_circle (center -0.9 -1.05) (end -0.849 -1.05)
      (stroke (width 0.15) (type solid)) (fill solid) (layer "F.SilkS"))
    (fp_rect (start -1.1 -1.25) (end 1.1 1.25)
      (stroke (width 0.05) (type solid)) (fill none) (layer "F.CrtYd"))
    (fp_line (start -1 -0.5) (end -0.5 -1)
      (stroke (width 0.15) (type solid)) (layer "F.Fab"))
    (fp_line (start -1 0.998) (end -1 -0.5)
      (stroke (width 0.15) (type solid)) (layer "F.Fab"))
    (fp_line (start -0.5 -1) (end 0.998 -1)
      (stroke (width 0.15) (type solid)) (layer "F.Fab"))
    (fp_line (start 0.998 -1) (end 0.998 0.998)
      (stroke (width 0.15) (type solid)) (layer "F.Fab"))
    (fp_line (start 0.998 0.998) (end -1 0.998)
      (stroke (width 0.15) (type solid)) (layer "F.Fab"))
    (pad "1" smd rect (at -0.677 -0.75 90) (size 0.55 0.25) (layers "F.Cu" "F.Paste" "F.Mask")
      (net 231 "/Power supply/VCCIO_EN") (pinfunction "EN") (pintype "input"))
    (pad "2" smd rect (at -0.677 -0.25 90) (size 0.55 0.25) (layers "F.Cu" "F.Paste" "F.Mask")
      (net 299 "Net-(U19-FB)") (pinfunction "FB") (pintype "bidirectional"))
    (pad "3" smd rect (at -0.677 0.248 90) (size 0.55 0.25) (layers "F.Cu" "F.Paste" "F.Mask")
      (net 1 "GND") (pinfunction "AGND") (pintype "power_in"))
    (pad "4" smd rect (at -0.677 0.748 90) (size 0.55 0.25) (layers "F.Cu" "F.Paste" "F.Mask")
      (net 545 "unconnected-(U19-NC-Pad4)") (pinfunction "NC") (pintype "no_connect"))
    (pad "5" smd rect (at 0.675 0.748 90) (size 0.55 0.25) (layers "F.Cu" "F.Paste" "F.Mask")
      (net 1 "GND") (pinfunction "PGND") (pintype "power_in"))
    (pad "6" smd rect (at 0.675 0.248 90) (size 0.55 0.25) (layers "F.Cu" "F.Paste" "F.Mask")
      (net 391 "Net-(U19-SW)") (pinfunction "SW") (pintype "bidirectional"))
    (pad "7" smd rect (at 0.675 -0.25 90) (size 0.55 0.25) (layers "F.Cu" "F.Paste" "F.Mask")
      (net 11 "VCC5V0") (pinfunction "VIN") (pintype "power_in"))
    (pad "8" smd rect (at 0.675 -0.75 90) (size 0.55 0.25) (layers "F.Cu" "F.Paste" "F.Mask")
      (net 224 "/Power supply/1V35_PG") (pinfunction "PG") (pintype "output"))
  )
	(footprint "antmicro-footprints:QFN-8_2x1.5mm" (layer "F.Cu")
    (at 71.05 86.15 90)
    (property "Author" "Antmicro")
    (property "License" "Apache-2.0")
    (property "MPN" "TPS62823DLCT")
    (property "Manufacturer" "Texas Instruments")
    (property "Sheetfile" "power-supply.kicad_sch")
    (property "Sheetname" "Power supply")
    (property "ki_description" "DC/DC converter")
    (property "ki_keywords" "SMT, PMIC, IC, SWITCHING, VOLTAGE, REGULATOR, DC-DC")
    (attr smd)
    (fp_text reference "U20" (at 0.295 1.65 90) (layer "F.SilkS")
        (effects (font (size 0.7 0.7) (thickness 0.127)))
    )
    (fp_text value "TPS62823DLCT" (at 0 2.075 90) (layer "F.Fab")
        (effects (font (size 1 1) (thickness 0.15)))
    )
    (fp_text user "License: Apache-2.0" (at -1.651 6.475 90) (layer "F.Fab") hide
        (effects (font (size 0.7 0.7) (thickness 0.15)) (justify left bottom))
    )
    (fp_text user "${REFERENCE}" (at 0 0 90) (layer "F.Fab")
        (effects (font (size 0.5 0.5) (thickness 0.075)))
    )
    (fp_text user "Author: Antmicro" (at -1.651 5.275 90) (layer "F.Fab") hide
        (effects (font (size 0.7 0.7) (thickness 0.15)) (justify left bottom))
    )
    (fp_line (start -0.9 1.05) (end 0.9 1.05)
      (stroke (width 0.15) (type solid)) (layer "F.SilkS"))
    (fp_line (start -0.25 -1.05) (end 0.9 -1.05)
      (stroke (width 0.15) (type solid)) (layer "F.SilkS"))
    (fp_circle (center -0.9 -1.05) (end -0.849 -1.05)
      (stroke (width 0.15) (type solid)) (fill solid) (layer "F.SilkS"))
    (fp_rect (start -1.1 -1.25) (end 1.1 1.25)
      (stroke (width 0.05) (type solid)) (fill none) (layer "F.CrtYd"))
    (fp_line (start -1 -0.5) (end -0.5 -1)
      (stroke (width 0.15) (type solid)) (layer "F.Fab"))
    (fp_line (start -1 0.998) (end -1 -0.5)
      (stroke (width 0.15) (type solid)) (layer "F.Fab"))
    (fp_line (start -0.5 -1) (end 0.998 -1)
      (stroke (width 0.15) (type solid)) (layer "F.Fab"))
    (fp_line (start 0.998 -1) (end 0.998 0.998)
      (stroke (width 0.15) (type solid)) (layer "F.Fab"))
    (fp_line (start 0.998 0.998) (end -1 0.998)
      (stroke (width 0.15) (type solid)) (layer "F.Fab"))
    (pad "1" smd rect (at -0.677 -0.75 90) (size 0.55 0.25) (layers "F.Cu" "F.Paste" "F.Mask")
      (net 366 "/Power supply/VCCA0_EN") (pinfunction "EN") (pintype "input"))
    (pad "2" smd rect (at -0.677 -0.25 90) (size 0.55 0.25) (layers "F.Cu" "F.Paste" "F.Mask")
      (net 300 "Net-(U20-FB)") (pinfunction "FB") (pintype "bidirectional"))
    (pad "3" smd rect (at -0.677 0.248 90) (size 0.55 0.25) (layers "F.Cu" "F.Paste" "F.Mask")
      (net 1 "GND") (pinfunction "AGND") (pintype "power_in"))
    (pad "4" smd rect (at -0.677 0.748 90) (size 0.55 0.25) (layers "F.Cu" "F.Paste" "F.Mask")
      (net 546 "unconnected-(U20-NC-Pad4)") (pinfunction "NC") (pintype "no_connect"))
    (pad "5" smd rect (at 0.675 0.748 90) (size 0.55 0.25) (layers "F.Cu" "F.Paste" "F.Mask")
      (net 1 "GND") (pinfunction "PGND") (pintype "power_in"))
    (pad "6" smd rect (at 0.675 0.248 90) (size 0.55 0.25) (layers "F.Cu" "F.Paste" "F.Mask")
      (net 392 "Net-(U20-SW)") (pinfunction "SW") (pintype "bidirectional"))
    (pad "7" smd rect (at 0.675 -0.25 90) (size 0.55 0.25) (layers "F.Cu" "F.Paste" "F.Mask")
      (net 11 "VCC5V0") (pinfunction "VIN") (pintype "power_in"))
    (pad "8" smd rect (at 0.675 -0.75 90) (size 0.55 0.25) (layers "F.Cu" "F.Paste" "F.Mask")
      (net 385 "1V0_PG") (pinfunction "PG") (pintype "output"))
  )
	(footprint "antmicro-footprints:R_0402_1005Metric" (layer "F.Cu")
    (at 76.75 88.7)
    (descr "Resistor SMD 0402")
    (tags "resistor SMD 0402")
    (property "Author" "Antmicro")
    (property "License" "Apache-2.0")
    (property "MPN" "CR0402-FX-1003GLF")
    (property "Manufacturer" "Bourns")
    (property "Public" "False")
    (property "Sheetfile" "power-supply.kicad_sch")
    (property "Sheetname" "Power supply")
    (property "Tolerance" "1%")
    (property "Val" "100k")
    (property "ki_description" "SMD Chip Resistor, 100 kohm, ± 1%, 62.5 mW, 0402 [1005 Metric], Thick Film, General Purpose")
    (property "ki_keywords" "0402, SMT, RESISTOR, PASSIVE")
    (attr smd)
    (fp_text reference "R119" (at -0.29 0.96) (layer "F.SilkS")
        (effects (font (size 0.7 0.7) (thickness 0.127)))
    )
    (fp_text value "R_100k_0402" (at 0 1.17) (layer "F.Fab")
        (effects (font (size 1 1) (thickness 0.15)))
    )
    (fp_text user "License: Apache-2.0" (at -0.95 5.169) (layer "F.Fab") hide
        (effects (font (size 0.7 0.7) (thickness 0.15)) (justify left bottom))
    )
    (fp_text user "Author: Antmicro" (at -0.95 4.169) (layer "F.Fab") hide
        (effects (font (size 0.7 0.7) (thickness 0.15)) (justify left bottom))
    )
    (fp_text user "${REFERENCE}" (at 0 0) (layer "F.Fab")
        (effects (font (size 0.25 0.25) (thickness 0.04)))
    )
    (fp_rect (start -0.925 -0.47) (end 0.925 0.47)
      (stroke (width 0.05) (type default)) (fill none) (layer "F.CrtYd"))
    (fp_rect (start -0.5 -0.25) (end 0.5 0.25)
      (stroke (width 0.15) (type solid)) (fill none) (layer "F.Fab"))
    (pad "1" smd roundrect (at -0.48 0) (size 0.59 0.64) (layers "F.Cu" "F.Paste" "F.Mask") (roundrect_rratio 0.25)
      (net 299 "Net-(U19-FB)") (pintype "passive"))
    (pad "2" smd roundrect (at 0.48 0) (size 0.59 0.64) (layers "F.Cu" "F.Paste" "F.Mask") (roundrect_rratio 0.25)
      (net 1 "GND") (pintype "passive"))
  )
	(footprint "antmicro-footprints:R_0402_1005Metric" (layer "F.Cu")
    (at 78.75 88.7 180)
    (descr "Resistor SMD 0402")
    (tags "resistor SMD 0402")
    (property "Author" "Antmicro")
    (property "License" "Apache-2.0")
    (property "MPN" "CR0402-FX-1243GLF")
    (property "Manufacturer" "Bourns")
    (property "Public" "False")
    (property "Sheetfile" "power-supply.kicad_sch")
    (property "Sheetname" "Power supply")
    (property "Tolerance" "1%")
    (property "Val" "124k")
    (property "ki_description" "SMD Chip Resistor, 124 kohm, ± 1%, 100 mW, 0402 [1005 Metric], Thick Film, Precision")
    (property "ki_keywords" "0402, SMT, RESISTOR, PASSIVE")
    (attr smd)
    (fp_text reference "R118" (at 1.05 -1.94) (layer "F.SilkS")
        (effects (font (size 0.7 0.7) (thickness 0.127)))
    )
    (fp_text value "R_124k_0402" (at 0 1.17) (layer "F.Fab")
        (effects (font (size 1 1) (thickness 0.15)))
    )
    (fp_text user "Author: Antmicro" (at -0.95 4.169 180) (layer "F.Fab") hide
        (effects (font (size 0.7 0.7) (thickness 0.15)) (justify left bottom))
    )
    (fp_text user "${REFERENCE}" (at 0 0) (layer "F.Fab")
        (effects (font (size 0.25 0.25) (thickness 0.04)))
    )
    (fp_text user "License: Apache-2.0" (at -0.95 5.169 180) (layer "F.Fab") hide
        (effects (font (size 0.7 0.7) (thickness 0.15)) (justify left bottom))
    )
    (fp_rect (start -0.925 -0.47) (end 0.925 0.47)
      (stroke (width 0.05) (type default)) (fill none) (layer "F.CrtYd"))
    (fp_rect (start -0.5 -0.25) (end 0.5 0.25)
      (stroke (width 0.15) (type solid)) (fill none) (layer "F.Fab"))
    (pad "1" smd roundrect (at -0.48 0 180) (size 0.59 0.64) (layers "F.Cu" "F.Paste" "F.Mask") (roundrect_rratio 0.25)
      (net 357 "Net-(C120-Pad2)") (pintype "passive"))
    (pad "2" smd roundrect (at 0.48 0 180) (size 0.59 0.64) (layers "F.Cu" "F.Paste" "F.Mask") (roundrect_rratio 0.25)
      (net 299 "Net-(U19-FB)") (pintype "passive"))
  )
	(footprint "antmicro-footprints:R_0402_1005Metric" (layer "F.Cu")
    (at 70.585 88.7 180)
    (descr "Resistor SMD 0402")
    (tags "resistor SMD 0402")
    (property "Author" "Antmicro")
    (property "License" "Apache-2.0")
    (property "MPN" "CR0402-FX-1003GLF")
    (property "Manufacturer" "Bourns")
    (property "Public" "False")
    (property "Sheetfile" "power-supply.kicad_sch")
    (property "Sheetname" "Power supply")
    (property "Tolerance" "1%")
    (property "Val" "100k")
    (property "ki_description" "SMD Chip Resistor, 100 kohm, ± 1%, 62.5 mW, 0402 [1005 Metric], Thick Film, General Purpose")
    (property "ki_keywords" "0402, SMT, RESISTOR, PASSIVE")
    (attr smd)
    (fp_text reference "R121" (at -0.515 0.925) (layer "F.SilkS")
        (effects (font (size 0.7 0.7) (thickness 0.127)))
    )
    (fp_text value "R_100k_0402" (at 0 1.17) (layer "F.Fab")
        (effects (font (size 1 1) (thickness 0.15)))
    )
    (fp_text user "License: Apache-2.0" (at -0.95 5.169 180) (layer "F.Fab") hide
        (effects (font (size 0.7 0.7) (thickness 0.15)) (justify left bottom))
    )
    (fp_text user "${REFERENCE}" (at 0 0) (layer "F.Fab")
        (effects (font (size 0.25 0.25) (thickness 0.04)))
    )
    (fp_text user "Author: Antmicro" (at -0.95 4.169 180) (layer "F.Fab") hide
        (effects (font (size 0.7 0.7) (thickness 0.15)) (justify left bottom))
    )
    (fp_rect (start -0.925 -0.47) (end 0.925 0.47)
      (stroke (width 0.05) (type default)) (fill none) (layer "F.CrtYd"))
    (fp_rect (start -0.5 -0.25) (end 0.5 0.25)
      (stroke (width 0.15) (type solid)) (fill none) (layer "F.Fab"))
    (pad "1" smd roundrect (at -0.48 0 180) (size 0.59 0.64) (layers "F.Cu" "F.Paste" "F.Mask") (roundrect_rratio 0.25)
      (net 1 "GND") (pintype "passive"))
    (pad "2" smd roundrect (at 0.48 0 180) (size 0.59 0.64) (layers "F.Cu" "F.Paste" "F.Mask") (roundrect_rratio 0.25)
      (net 300 "Net-(U20-FB)") (pintype "passive"))
  )
	(footprint "antmicro-footprints:R_0402_1005Metric" (layer "F.Cu")
    (at 117.524056 86.193104)
    (descr "Resistor SMD 0402")
    (tags "resistor SMD 0402")
    (property "Author" "Antmicro")
    (property "License" "Apache-2.0")
    (property "MPN" "CR0402-FX-1003GLF")
    (property "Manufacturer" "Bourns")
    (property "Public" "False")
    (property "Sheetfile" "power-supply.kicad_sch")
    (property "Sheetname" "Power supply")
    (property "Tolerance" "1%")
    (property "Val" "100k")
    (property "ki_description" "SMD Chip Resistor, 100 kohm, ± 1%, 62.5 mW, 0402 [1005 Metric], Thick Film, General Purpose")
    (property "ki_keywords" "0402, SMT, RESISTOR, PASSIVE")
    (attr smd)
    (fp_text reference "R117" (at -1.235 -0.94) (layer "F.SilkS")
        (effects (font (size 0.7 0.7) (thickness 0.127)))
    )
    (fp_text value "R_100k_0402" (at 0 1.17) (layer "F.Fab")
        (effects (font (size 1 1) (thickness 0.15)))
    )
    (fp_text user "Author: Antmicro" (at -0.95 4.169) (layer "F.Fab") hide
        (effects (font (size 0.7 0.7) (thickness 0.15)) (justify left bottom))
    )
    (fp_text user "License: Apache-2.0" (at -0.95 5.169) (layer "F.Fab") hide
        (effects (font (size 0.7 0.7) (thickness 0.15)) (justify left bottom))
    )
    (fp_text user "${REFERENCE}" (at 0 0) (layer "F.Fab")
        (effects (font (size 0.25 0.25) (thickness 0.04)))
    )
    (fp_rect (start -0.925 -0.47) (end 0.925 0.47)
      (stroke (width 0.05) (type default)) (fill none) (layer "F.CrtYd"))
    (fp_rect (start -0.5 -0.25) (end 0.5 0.25)
      (stroke (width 0.15) (type solid)) (fill none) (layer "F.Fab"))
    (pad "1" smd roundrect (at -0.48 0) (size 0.59 0.64) (layers "F.Cu" "F.Paste" "F.Mask") (roundrect_rratio 0.25)
      (net 292 "Net-(U18-FB)") (pintype "passive"))
    (pad "2" smd roundrect (at 0.48 0) (size 0.59 0.64) (layers "F.Cu" "F.Paste" "F.Mask") (roundrect_rratio 0.25)
      (net 1 "GND") (pintype "passive"))
  )
	(footprint "antmicro-footprints:R_0402_1005Metric" (layer "F.Cu")
    (at 119.589056 86.193104 180)
    (descr "Resistor SMD 0402")
    (tags "resistor SMD 0402")
    (property "Author" "Antmicro")
    (property "License" "Apache-2.0")
    (property "MPN" "CR0402-FX-2003GLF")
    (property "Manufacturer" "Bourns")
    (property "Public" "False")
    (property "Sheetfile" "power-supply.kicad_sch")
    (property "Sheetname" "Power supply")
    (property "Tolerance" "1%")
    (property "Val" "200k")
    (property "ki_description" "SMD Chip Resistor, 200 kohm, ± 1%, 62.5 mW, 0402 [1005 Metric], Thick Film, General Purpose")
    (property "ki_keywords" "0402, SMT, RESISTOR, PASSIVE")
    (attr smd)
    (fp_text reference "R116" (at 0.1 0.94) (layer "F.SilkS")
        (effects (font (size 0.7 0.7) (thickness 0.127)))
    )
    (fp_text value "R_200k_0402" (at 0 1.17) (layer "F.Fab")
        (effects (font (size 1 1) (thickness 0.15)))
    )
    (fp_text user "License: Apache-2.0" (at -0.95 5.169 180) (layer "F.Fab") hide
        (effects (font (size 0.7 0.7) (thickness 0.15)) (justify left bottom))
    )
    (fp_text user "${REFERENCE}" (at 0 0) (layer "F.Fab")
        (effects (font (size 0.25 0.25) (thickness 0.04)))
    )
    (fp_text user "Author: Antmicro" (at -0.95 4.169 180) (layer "F.Fab") hide
        (effects (font (size 0.7 0.7) (thickness 0.15)) (justify left bottom))
    )
    (fp_rect (start -0.925 -0.47) (end 0.925 0.47)
      (stroke (width 0.05) (type default)) (fill none) (layer "F.CrtYd"))
    (fp_rect (start -0.5 -0.25) (end 0.5 0.25)
      (stroke (width 0.15) (type solid)) (fill none) (layer "F.Fab"))
    (pad "1" smd roundrect (at -0.48 0 180) (size 0.59 0.64) (layers "F.Cu" "F.Paste" "F.Mask") (roundrect_rratio 0.25)
      (net 356 "Net-(C119-Pad2)") (pintype "passive"))
    (pad "2" smd roundrect (at 0.48 0 180) (size 0.59 0.64) (layers "F.Cu" "F.Paste" "F.Mask") (roundrect_rratio 0.25)
      (net 292 "Net-(U18-FB)") (pintype "passive"))
  )
	(footprint "antmicro-footprints:R_0402_1005Metric" (layer "F.Cu")
    (at 82.635 88.7)
    (descr "Resistor SMD 0402")
    (tags "resistor SMD 0402")
    (property "Author" "Antmicro")
    (property "License" "Apache-2.0")
    (property "MPN" "CR0402-FX-1003GLF")
    (property "Manufacturer" "Bourns")
    (property "Public" "False")
    (property "Sheetfile" "power-supply.kicad_sch")
    (property "Sheetname" "Power supply")
    (property "Tolerance" "1%")
    (property "Val" "100k")
    (property "ki_description" "SMD Chip Resistor, 100 kohm, ± 1%, 62.5 mW, 0402 [1005 Metric], Thick Film, General Purpose")
    (property "ki_keywords" "0402, SMT, RESISTOR, PASSIVE")
    (attr smd)
    (fp_text reference "R115" (at -0.285 1) (layer "F.SilkS")
        (effects (font (size 0.7 0.7) (thickness 0.127)))
    )
    (fp_text value "R_100k_0402" (at 0 1.17) (layer "F.Fab")
        (effects (font (size 1 1) (thickness 0.15)))
    )
    (fp_text user "${REFERENCE}" (at 0 0) (layer "F.Fab")
        (effects (font (size 0.25 0.25) (thickness 0.04)))
    )
    (fp_text user "License: Apache-2.0" (at -0.95 5.169) (layer "F.Fab") hide
        (effects (font (size 0.7 0.7) (thickness 0.15)) (justify left bottom))
    )
    (fp_text user "Author: Antmicro" (at -0.95 4.169) (layer "F.Fab") hide
        (effects (font (size 0.7 0.7) (thickness 0.15)) (justify left bottom))
    )
    (fp_rect (start -0.925 -0.47) (end 0.925 0.47)
      (stroke (width 0.05) (type default)) (fill none) (layer "F.CrtYd"))
    (fp_rect (start -0.5 -0.25) (end 0.5 0.25)
      (stroke (width 0.15) (type solid)) (fill none) (layer "F.Fab"))
    (pad "1" smd roundrect (at -0.48 0) (size 0.59 0.64) (layers "F.Cu" "F.Paste" "F.Mask") (roundrect_rratio 0.25)
      (net 291 "Net-(U17-FB)") (pintype "passive"))
    (pad "2" smd roundrect (at 0.48 0) (size 0.59 0.64) (layers "F.Cu" "F.Paste" "F.Mask") (roundrect_rratio 0.25)
      (net 1 "GND") (pintype "passive"))
  )
)
